FILE_TYPE = CONNECTIVITY;
{Allegro Design Entry HDL 17.2-2016 S081 (4005846) 1/11/2022}
"PAGE_NUMBER" = 264;
0"NC";
1"PVCCD_HV_CPU0\g";
2"P3V3_AUX\g";
3"PVNN_TERM_CPU0\g";
4"P3V3_AUX\g";
5"P3V3_AUX\g";
6"P3V3_AUX\g";
7"GND\g";
8"GND\g";
9"GND\g";
10"GND\g";
11"GND\g";
12"GND\g";
13"GND\g";
14"GND\g";
15"GND\g";
16"GND\g";
17"GND\g";
18"GND\g";
19"GND\g";
20"GND\g";
21"GND\g";
22"GND\g";
23"GND\g";
24"GND\g";
25"GND\g";
26"GND\g";
27"GND\g";
28"VSENSE_PVCCD_HV_CPU0_DN";
29"SMB_CLK_PVCCD_HV_CPU0";
30"SVID_DIO_PVCCD_HV_CPU0_R";
31"SVID_ALERT_PVCCD_HV_CPU0_R";
32"NC_PVCCD_HV_CPU0_BVR_RDY";
33"SVID_CLK_PVCCD_HV_CPU0_R";
34"NC_PVCCD_HV_CPU0_SMB_ALERT";
35"PVCCD_HV_CPU0_EN_R";
36"SMB_DIO_PVCCD_HV_CPU0";
37"SH_PVCCD_HV_CPU0_R";
38"PWRGD_PVCCD_HV_CPU0_R";
39"PVCCD_HV_CPU0_ISENSE_P";
40"PVCCD_HV_CPU0_ISENSE_N";
41"PVCCD_HV_CPU0_PIN_ALT";
42"PVCCD_HV_CPU0_FAULT";
43"PVCCD_HV_CPU0_ADDR";
44"NC_PVCCD_HV_CPU0_ACSP8";
45"NC_PVCCD_HV_CPU0_APWM8";
46"PVCCD_HV_CPU0_ATSEN";
47"NC_PVCCD_HV_CPU0_ACSP6";
48"NC_PVCCD_HV_CPU0_APWM6";
49"NC_PVCCD_HV_CPU0_ACSP5";
50"NC_PVCCD_HV_CPU0_APWM5";
51"PVCCD_HV_CPU0_APWM1";
52"NC_PVCCD_HV_CPU0_ACSP7";
53"PVCCD_HV_CPU0_ISYS_R";
54"PVCCD_HV_CPU0_VREF";
55"NC_PVCCD_HV_CPU0_APWM2";
56"NC_PVCCD_HV_CPU0_APWM7";
57"NC_PVCCD_HV_CPU0_APWM3";
58"NC_PVCCD_HV_CPU0_APWM4";
59"NC_PVCCD_HV_CPU0_ACSP4";
60"NC_PVCCD_HV_CPU0_ACSP3";
61"IRQ_PVCCD_CPU0_VRHOT_LVC3_R_N";
62"NC_PVCCD_HV_CPU0_ACSP2";
63"PVCCD_HV_CPU0_VCC";
64"PVCCD_HV_CPU0_ACSP1";
65"SVID_DIO1_CPU0_R";
66"VSENSE_PVCCD_HV_CPU0_DP";
67"SVID_CLK1_CPU0_R";
68"FM_PVCCD_HV_CPU0_EN";
69"SVID_ALERT1_CPU0_R_N";
70"PWRGD_PVCCD_HV_CPU0";
71"SH_PVCCD_HV_CPU0";
72"IRQ_PVCCD_CPU0_VRHOT_LVC3_N";
73"PVCCD_HV_CPU0_NVDIMM_ISENSE";
74"P12V_AUX_CPU0_DIMM_ISEN_N";
75"P12V_AUX_CPU0_DIMM_ISEN_P";
76"PVCCD_HV_CPU0_VREF";
77"SMB_VR_3V3AUX_SDA_R2";
78"SMB_VR_3V3AUX_SCL_R2";
%"Q_RES"
"1","(-9775,3500)","0","pure_quanta","I10";
;
PART_NUMBER"CS04992FB07"
TOLERANCE"1%"
VALUE"49.9"
MATERIAL"CHIP"
WATTAGE"1/16W"
PACK_TYPE"0402LF"
LOCATION"PR1390"
CDS_LIB"pure_quanta"
$SEC"1"
CDS_SEC"1";
"B"
$PN"2"40;
"A"
$PN"1"74;
%"Q_RES"
"1","(-9775,3600)","0","pure_quanta","I11";
;
PART_NUMBER"CS04992FB07"
TOLERANCE"1%"
MATERIAL"CHIP"
VALUE"49.9"
LOCATION"PR1380"
PACK_TYPE"0402LF"
WATTAGE"1/16W"
CDS_LIB"pure_quanta"
$SEC"1"
CDS_SEC"1";
"B"
$PN"2"39;
"A"
$PN"1"75;
%"Q_RES"
"2","(-9600,5250)","0","pure_quanta","I13";
;
PART_NUMBER"CS21002FB06"
PACK_TYPE"0402LF"
VALUE"1K"
TOLERANCE"1%"
MATERIAL"CHIP"
WATTAGE"1/16W"
LOCATION"PR370"
CDS_LIB"pure_quanta"
LOCATION"PR370"
$SEC"1"
CDS_SEC"1";
"A"
$PN"1"4;
"B"
$PN"2"41;
%"Q_RES"
"2","(-9275,5250)","0","pure_quanta","I14";
;
PART_NUMBER"CS21002FB06"
TOLERANCE"1%"
WATTAGE"1/16W"
PACK_TYPE"0402LF"
VALUE"1K"
MATERIAL"CHIP"
LOCATION"PR372"
CDS_LIB"pure_quanta"
LOCATION"PR372"
$SEC"1"
CDS_SEC"1";
"A"
$PN"1"4;
"B"
$PN"2"42;
%"UNIVERSAL_GND"
"1","(-12100,8325)","0","logical_power","I17";
;
HDL_POWER"GND"
CDS_LIB"logical_power";
"A"9;
%"Q_CAP"
"1","(-12100,8675)","0","pure_quanta","I18";
;
PART_NUMBER"CH6101MEB03"
TOLERANCE"20%"
MATERIAL"X6S"
VOLTAGE"6.3V"
VALUE"10UF"
PACK_TYPE"C0402"
LOCATION"C2443"
CDS_LIB"pure_quanta"
$SEC"1"
CDS_SEC"1";
"B"
$PN"2"9;
"A"
$PN"1"3;
%"Q_CAP"
"1","(-11875,8675)","0","pure_quanta","I19";
;
PART_NUMBER"CH4104K1B00"
VALUE"0.1UF"
VOLTAGE"25V"
TOLERANCE"10%"
MATERIAL"X7R"
PACK_TYPE"0402"
LOCATION"C2444"
CDS_LIB"pure_quanta"
$SEC"1"
CDS_SEC"1";
"B"
$PN"2"9;
"A"
$PN"1"3;
%"VCC15"
"1","(-12100,8950)","0","logical_power","I20";
;
HDL_POWER"PVNN_TERM_CPU0"
CDS_LIB"logical_power";
"A"3;
%"Q_RES"
"1","(-11350,8575)","0","pure_quanta","I24";
;
PART_NUMBER"CS11002FB07"
MATERIAL"CHIP"
TOLERANCE"1%"
VALUE"100"
LOCATION"R1735"
CDS_LIB"pure_quanta"
PACK_TYPE"0402LF"
WATTAGE"1/16W"
$SEC"1"
CDS_SEC"1";
"B"
$PN"2"65;
"A"
$PN"1"3;
%"Q_RES"
"1","(-11350,8675)","0","pure_quanta","I25";
;
PART_NUMBER"CS04992FB07"
MATERIAL"CHIP"
PACK_TYPE"0402LF"
VALUE"49.9"
WATTAGE"1/16W"
TOLERANCE"1%"
LOCATION"R1717"
CDS_LIB"pure_quanta"
$SEC"1"
CDS_SEC"1";
"B"
$PN"2"67;
"A"
$PN"1"3;
%"Q_RES"
"1","(-10525,6425)","0","pure_quanta","I30";
;
PART_NUMBER"CS11002FB07"
TOLERANCE"1%"
WATTAGE"1/16W"
VALUE"100"
MATERIAL"CHIP"
PACK_TYPE"0402LF"
LOCATION"PR591"
CDS_LIB"pure_quanta"
$SEC"1"
CDS_SEC"1";
"B"
$PN"2"10;
"A"
$PN"1"28;
%"Q_RES"
"1","(-10475,7100)","0","pure_quanta","I31";
;
PART_NUMBER"CS11002FB07"
WATTAGE"1/16W"
TOLERANCE"1%"
MATERIAL"CHIP"
VALUE"100"
PACK_TYPE"0402LF"
LOCATION"PR592"
CDS_LIB"pure_quanta"
$SEC"1"
CDS_SEC"1";
"B"
$PN"2"1;
"A"
$PN"1"66;
%"Q_SHORT"
"1","(-10550,6950)","0","pure_quanta","I32";
;
PART_NUMBER"SHORT6"
MATERIAL"EMPTY"
PACK_TYPE"SM"
LOCATION"PJ54"
CDS_LIB"pure_quanta"
NEEDS_NO_SIZE"TRUE"
LOCATION"PJ54"
$SEC"1"
CDS_SEC"1";
"1"
$PN"1"66;
"2"
$PN"2"71;
%"UNIVERSAL_GND"
"1","(-10000,6325)","0","logical_power","I33";
;
HDL_POWER"GND"
CDS_LIB"logical_power";
"A"10;
%"VCC15"
"1","(-9975,7250)","0","logical_power","I34";
;
HDL_POWER"PVCCD_HV_CPU0"
CDS_LIB"logical_power";
"A"1;
%"VCC15"
"1","(-9600,5600)","0","logical_power","I35";
;
HDL_POWER"P3V3_AUX"
CDS_LIB"logical_power";
"A"4;
%"Q_RES"
"1","(-9450,6950)","0","pure_quanta","I36";
;
PART_NUMBER"CS00002JB13"
MATERIAL"CHIP"
WATTAGE"1/16W"
PACK_TYPE"0402LF"
VALUE"0"
TOLERANCE"5%"
LOCATION"PR371"
CDS_LIB"pure_quanta"
LOCATION"PR371"
$SEC"1"
CDS_SEC"1";
"B"
$PN"2"37;
"A"
$PN"1"71;
%"Q_CAP"
"1","(-9000,6775)","0","pure_quanta","I37";
;
PART_NUMBER"TMP_QCH2336K1B12"
PACK_TYPE"0402"
VALUE"3300PF"
VOLTAGE"50V"
TOLERANCE"10%"
MATERIAL"X7R"
LOCATION"PC627"
CDS_LIB"pure_quanta"
LOCATION"PC627"
$SEC"1"
CDS_SEC"1";
"B"
$PN"2"28;
"A"
$PN"1"37;
%"Q_RES"
"1","(-9850,7650)","0","pure_quanta","I38";
;
PART_NUMBER"CS00002JB13"
MATERIAL"CHIP"
PACK_TYPE"0402LF"
WATTAGE"1/16W"
VALUE"0"
TOLERANCE"5%"
LOCATION"R2403"
CDS_LIB"pure_quanta"
LOCATION"R2403"
$SEC"1"
CDS_SEC"1";
"B"
$PN"2"36;
"A"
$PN"1"77;
%"Q_RES"
"1","(-9850,7800)","0","pure_quanta","I39";
;
PART_NUMBER"CS00002JB13"
PACK_TYPE"0402LF"
TOLERANCE"5%"
VALUE"0"
WATTAGE"1/16W"
MATERIAL"CHIP"
LOCATION"R2402"
CDS_LIB"pure_quanta"
LOCATION"R2402"
$SEC"1"
CDS_SEC"1";
"B"
$PN"2"29;
"A"
$PN"1"78;
%"UNIVERSAL_GND"
"1","(-11350,3650)","0","logical_power","I4";
;
HDL_POWER"GND"
CDS_LIB"logical_power";
"A"7;
%"Q_RES"
"1","(-9850,8200)","0","pure_quanta","I40";
;
PART_NUMBER"CS00002JB13"
WATTAGE"1/16W"
MATERIAL"CHIP"
VALUE"0"
PACK_TYPE"0402LF"
TOLERANCE"5%"
LOCATION"R2401"
CDS_LIB"pure_quanta"
LOCATION"R2401"
$SEC"1"
CDS_SEC"1";
"B"
$PN"2"31;
"A"
$PN"1"69;
%"VCC15"
"1","(-10275,9200)","0","logical_power","I41";
;
HDL_POWER"P3V3_AUX"
CDS_LIB"logical_power";
"A"5;
%"Q_RES"
"1","(-9850,8350)","0","pure_quanta","I42";
;
PART_NUMBER"CS00002JB13"
TOLERANCE"5%"
WATTAGE"1/16W"
PACK_TYPE"0402LF"
VALUE"0"
MATERIAL"CHIP"
LOCATION"R2400"
CDS_LIB"pure_quanta"
LOCATION"R2400"
$SEC"1"
CDS_SEC"1";
"B"
$PN"2"30;
"A"
$PN"1"65;
%"Q_RES"
"1","(-9850,8500)","0","pure_quanta","I43";
;
PART_NUMBER"CS11502FB07"
WATTAGE"1/16W"
PACK_TYPE"0402LF"
VALUE"150"
TOLERANCE"1%"
MATERIAL"CHIP"
LOCATION"R2399"
CDS_LIB"pure_quanta"
LOCATION"R2399"
$SEC"1"
CDS_SEC"1";
"B"
$PN"2"33;
"A"
$PN"1"67;
%"Q_RES"
"1","(-9850,8950)","0","pure_quanta","I44";
;
PART_NUMBER"CS00002JB13"
PACK_TYPE"0402LF"
MATERIAL"CHIP"
TOLERANCE"5%"
WATTAGE"1/16W"
VALUE"0"
LOCATION"R362"
CDS_LIB"pure_quanta"
LOCATION"R362"
$SEC"1"
CDS_SEC"1";
"B"
$PN"2"38;
"A"
$PN"1"70;
%"Q_RES"
"1","(-9850,8800)","0","pure_quanta","I45";
;
PART_NUMBER"CS00002JB13"
TOLERANCE"5%"
PACK_TYPE"0402LF"
MATERIAL"CHIP"
VALUE"0"
WATTAGE"1/16W"
LOCATION"R363"
CDS_LIB"pure_quanta"
LOCATION"R363"
$SEC"1"
CDS_SEC"1";
"B"
$PN"2"35;
"A"
$PN"1"68;
%"Q_RES"
"1","(-9850,9100)","0","pure_quanta","I46";
;
PART_NUMBER"CS21002FB06"
PACK_TYPE"0402LF"
WATTAGE"1/16W"
VALUE"1K"
TOLERANCE"1%"
MATERIAL"CHIP"
LOCATION"R361"
CDS_LIB"pure_quanta"
LOCATION"R361"
$SEC"1"
CDS_SEC"1";
"B"
$PN"2"38;
"A"
$PN"1"5;
%"Q_CAP"
"2","(-9000,9100)","0","pure_quanta","I47";
;
PART_NUMBER"TMP_QCH21006JB10"
TOLERANCE"5%"
PACK_TYPE"0402"
VALUE"1000PF"
VOLTAGE"50V"
MATERIAL"EMPTY"
LOCATION"C626"
CDS_LIB"pure_quanta"
LOCATION"C626"
$SEC"1"
CDS_SEC"1";
"A"
$PN"1"38;
"B"
$PN"2"17;
%"Q_RES"
"2","(-8600,3175)","2","pure_quanta","I48";
;
PART_NUMBER"CS21002FB06"
PACK_TYPE"0402LF"
VALUE"1K"
MATERIAL"EMPTY"
WATTAGE"1/16W"
TOLERANCE"1%"
LOCATION"PR373"
CDS_LIB"pure_quanta"
LOCATION"PR373"
$SEC"1"
CDS_SEC"1";
"A"
$PN"1"40;
"B"
$PN"2"11;
%"UNIVERSAL_GND"
"1","(-8475,2875)","0","logical_power","I49";
;
HDL_POWER"GND"
CDS_LIB"logical_power";
"A"11;
%"Q_RES"
"1","(-10725,3850)","0","pure_quanta","I5";
;
PART_NUMBER"CS32802FB05"
WATTAGE"1/16W"
PACK_TYPE"0402LF"
TOLERANCE"1%"
VALUE"28K"
MATERIAL"EMPTY"
LOCATION"PR357"
CDS_LIB"pure_quanta"
LOCATION"PR357"
$SEC"1"
CDS_SEC"1";
"B"
$PN"2"43;
"A"
$PN"1"76;
%"Q_CAP"
"1","(-8475,3175)","0","pure_quanta","I50";
;
PART_NUMBER"CH4104K1B00"
PACK_TYPE"0402"
VALUE"0.1UF"
TOLERANCE"10%"
MATERIAL"X7R"
VOLTAGE"25V"
LOCATION"PC628"
CDS_LIB"pure_quanta"
LOCATION"PC628"
$SEC"1"
CDS_SEC"1";
"B"
$PN"2"11;
"A"
$PN"1"40;
%"Q_CAP"
"2","(-8575,3550)","0","pure_quanta","I51";
;
PART_NUMBER"CH5103KEB01"
PACK_TYPE"C0402"
VALUE"1UF"
TOLERANCE"10%"
MATERIAL"X6S"
VOLTAGE"16V"
LOCATION"PC813"
CDS_LIB"pure_quanta"
$SEC"1"
CDS_SEC"1";
"A"
$PN"1"40;
"B"
$PN"2"39;
%"UNIVERSAL_GND"
"1","(-8250,3275)","0","logical_power","I52";
;
HDL_POWER"GND"
CDS_LIB"logical_power";
"A"12;
%"ISL69260IRAZT"
"1","(-7475,6200)","0","pure_quanta","I53";
;
PART_NUMBER"AL069260000"
VALUE"ISL69260IRAZ-T"
PART_TYPE"SMLF"
MATERIAL"IC"
LOCATION"PU35"
CDS_LIB"pure_quanta"
CDS_LMAN_SYM_OUTLINE"-550,2850,500,-2850"
NEEDS_NO_SIZE"TRUE"
$SEC"1"
CDS_SEC"1";
"CS0"
$PN"30"44;
"PWM0"
$PN"1"45;
"TEMP0"
$PN"35"46;
"ADDR_CFG"
$PN"34"43;
"TH_GND"
$PN"TH"12;
"CFP"
$PN"33"42;
"CS2"
$PN"28"47;
"PWM2"
$PN"3"48;
"CS3"
$PN"27"49;
"PWM3"
$PN"4"50;
"PWM7"
$PN"8"51;
"CS1"
$PN"29"52;
"RGND1"
$PN"31"16;
"VSEN1"
$PN"32"16;
"NPINALERT#||NPSYSCRIT# \B"
$PN"15"41;
"TEMP1||ISYS"
$PN"36"53;
"VINSEN||VSYS"
$PN"38"40;
"VMON||IINSEN||VSYS||ISYS"
$PN"37"39;
"VCCS"
$PN"40"54;
"PWM6"
$PN"7"55;
"PG0"
$PN"12"38;
"PWM1"
$PN"2"56;
"VSEN0"
$PN"21"37;
"PWM5"
$PN"6"57;
"PWM4"
$PN"5"58;
"PMSDA"
$PN"9"36;
"RGND0"
$PN"22"28;
"EN0"
$PN"13"35;
"NPMALERT# \B"
$PN"11"34;
"SVCLK"
$PN"17"33;
"PG1"
$PN"16"32;
"CS4"
$PN"26"59;
"CS5"
$PN"25"60;
"NVRHOT# \B"
$PN"14"61;
"NSVALERT# \B"
$PN"19"31;
"CS6"
$PN"24"62;
"SVDATA"
$PN"18"30;
"PMSCL"
$PN"10"29;
"EN1"
$PN"20"13;
"VCC"
$PN"39"63;
"CS7"
$PN"23"64;
%"UNIVERSAL_GND"
"1","(-8300,4425)","0","logical_power","I54";
;
HDL_POWER"GND"
CDS_LIB"logical_power";
"A"13;
%"UNIVERSAL_GND"
"1","(-5850,3325)","0","logical_power","I55";
;
HDL_POWER"GND"
CDS_LIB"logical_power";
"A"14;
%"Q_CAP"
"1","(-5850,3550)","0","pure_quanta","I56";
;
PART_NUMBER"TMP_QCH14706KB18"
PACK_TYPE"0402"
VOLTAGE"50V"
VALUE"470PF"
TOLERANCE"10%"
MATERIAL"X7R"
LOCATION"PC631"
CDS_LIB"pure_quanta"
LOCATION"PC631"
$SEC"1"
CDS_SEC"1";
"B"
$PN"2"14;
"A"
$PN"1"46;
%"Q_RES"
"2","(-5150,3550)","0","pure_quanta","I57";
;
PART_NUMBER"CS31002FB08"
TOLERANCE"1%"
VALUE"10K"
MATERIAL"EMPTY"
PACK_TYPE"0402LF"
WATTAGE"1/16W"
LOCATION"PR634"
CDS_LIB"pure_quanta"
$SEC"1"
CDS_SEC"1";
"A"
$PN"1"46;
"B"
$PN"2"15;
%"UNIVERSAL_GND"
"1","(-5150,3300)","0","logical_power","I58";
;
HDL_POWER"GND"
CDS_LIB"logical_power";
"A"15;
%"Q_RES"
"1","(-4975,4050)","0","pure_quanta","I59";
;
PART_NUMBER"CS00002JB13"
PACK_TYPE"0402LF"
WATTAGE"1/16W"
TOLERANCE"5%"
VALUE"0"
MATERIAL"CHIP"
LOCATION"PR1311"
CDS_LIB"pure_quanta"
$SEC"1"
CDS_SEC"1";
"B"
$PN"2"20;
"A"
$PN"1"53;
%"Q_RES"
"1","(-5325,4450)","0","pure_quanta","I60";
;
PART_NUMBER"CS00002JB13"
WATTAGE"1/16W"
PACK_TYPE"0402LF"
VALUE"0"
TOLERANCE"5%"
MATERIAL"CHIP"
LOCATION"R2405"
CDS_LIB"pure_quanta"
$SEC"1"
CDS_SEC"1";
"B"
$PN"2"72;
"A"
$PN"1"61;
%"Q_RES"
"1","(-5200,4700)","0","pure_quanta","I61";
;
PART_NUMBER"CS00002JB13"
PACK_TYPE"0402LF"
WATTAGE"1/16W"
TOLERANCE"5%"
MATERIAL"CHIP"
VALUE"0"
LOCATION"PR4236"
CDS_LIB"pure_quanta"
$SEC"1"
CDS_SEC"1";
"B"
$PN"2"21;
"A"
$PN"1"44;
%"Q_RES"
"1","(-5200,5150)","0","pure_quanta","I62";
;
PART_NUMBER"CS00002JB13"
PACK_TYPE"0402LF"
VALUE"0"
WATTAGE"1/16W"
TOLERANCE"5%"
MATERIAL"CHIP"
LOCATION"PR4235"
CDS_LIB"pure_quanta"
$SEC"1"
CDS_SEC"1";
"B"
$PN"2"22;
"A"
$PN"1"52;
%"Q_RES"
"1","(-4875,4300)","0","pure_quanta","I63";
;
PART_NUMBER"CS00002JB13"
WATTAGE"1/16W"
MATERIAL"EMPTY"
PACK_TYPE"0402LF"
VALUE"0"
TOLERANCE"5%"
LOCATION"PR409"
CDS_LIB"pure_quanta"
$SEC"1"
CDS_SEC"1";
"B"
$PN"2"73;
"A"
$PN"1"53;
%"UNIVERSAL_GND"
"1","(-8350,5350)","0","logical_power","I64";
;
HDL_POWER"GND"
CDS_LIB"logical_power";
"A"16;
%"UNIVERSAL_GND"
"1","(-8300,9100)","1","logical_power","I65";
;
HDL_POWER"GND"
CDS_LIB"logical_power";
"A"17;
%"Q_RES"
"1","(-5200,5600)","0","pure_quanta","I66";
;
PART_NUMBER"CS00002JB13"
WATTAGE"1/16W"
TOLERANCE"5%"
PACK_TYPE"0402LF"
VALUE"0"
MATERIAL"CHIP"
LOCATION"PR4234"
CDS_LIB"pure_quanta"
$SEC"1"
CDS_SEC"1";
"B"
$PN"2"23;
"A"
$PN"1"47;
%"Q_RES"
"1","(-5200,6050)","0","pure_quanta","I67";
;
PART_NUMBER"CS00002JB13"
WATTAGE"1/16W"
PACK_TYPE"0402LF"
TOLERANCE"5%"
VALUE"0"
MATERIAL"CHIP"
LOCATION"PR4233"
CDS_LIB"pure_quanta"
$SEC"1"
CDS_SEC"1";
"B"
$PN"2"24;
"A"
$PN"1"49;
%"Q_RES"
"1","(-5200,6500)","0","pure_quanta","I68";
;
PART_NUMBER"CS00002JB13"
PACK_TYPE"0402LF"
MATERIAL"CHIP"
TOLERANCE"5%"
VALUE"0"
WATTAGE"1/16W"
LOCATION"PR4232"
CDS_LIB"pure_quanta"
$SEC"1"
CDS_SEC"1";
"B"
$PN"2"25;
"A"
$PN"1"59;
%"Q_RES"
"1","(-5200,6950)","0","pure_quanta","I69";
;
PART_NUMBER"CS00002JB13"
MATERIAL"CHIP"
PACK_TYPE"0402LF"
TOLERANCE"5%"
VALUE"0"
WATTAGE"1/16W"
LOCATION"PR4231"
CDS_LIB"pure_quanta"
$SEC"1"
CDS_SEC"1";
"B"
$PN"2"26;
"A"
$PN"1"60;
%"Q_RES"
"2","(-9350,3175)","2","pure_quanta","I7";
;
PART_NUMBER"CS21002FB06"
PACK_TYPE"0402LF"
VALUE"1K"
TOLERANCE"1%"
MATERIAL"EMPTY"
WATTAGE"1/16W"
LOCATION"PR369"
CDS_LIB"pure_quanta"
LOCATION"PR369"
$SEC"1"
CDS_SEC"1";
"A"
$PN"1"39;
"B"
$PN"2"8;
%"Q_CAP"
"1","(-6225,8275)","0","pure_quanta","I70";
;
PART_NUMBER"CH6101MEB03"
VOLTAGE"6.3V"
VALUE"10UF"
TOLERANCE"20%"
PACK_TYPE"C0402"
MATERIAL"X6S"
LOCATION"PC630"
CDS_LIB"pure_quanta"
LOCATION"PC630"
$SEC"1"
CDS_SEC"1";
"B"
$PN"2"18;
"A"
$PN"1"54;
%"Q_CAP"
"1","(-5825,8275)","0","pure_quanta","I71";
;
PART_NUMBER"CH5103KEB01"
PACK_TYPE"C0402"
MATERIAL"X6S"
TOLERANCE"10%"
VOLTAGE"16V"
VALUE"1UF"
LOCATION"PC1196"
CDS_LIB"pure_quanta"
$SEC"1"
CDS_SEC"1";
"B"
$PN"2"18;
"A"
$PN"1"54;
%"Q_CAP"
"1","(-6225,8750)","0","pure_quanta","I72";
;
PART_NUMBER"CH4106K1B01"
VOLTAGE"50V"
TOLERANCE"10%"
VALUE"100NF"
PACK_TYPE"C0402"
MATERIAL"EMPTY"
LOCATION"PC629"
CDS_LIB"pure_quanta"
LOCATION"PC629"
$SEC"1"
CDS_SEC"1";
"B"
$PN"2"19;
"A"
$PN"1"63;
%"Q_CAP"
"1","(-5825,8750)","0","pure_quanta","I73";
;
PART_NUMBER"CH5103KEB01"
MATERIAL"X6S"
VOLTAGE"16V"
VALUE"1UF"
TOLERANCE"10%"
PACK_TYPE"C0402"
LOCATION"PC632"
CDS_LIB"pure_quanta"
LOCATION"PC632"
$SEC"1"
CDS_SEC"1";
"B"
$PN"2"19;
"A"
$PN"1"63;
%"Q_RES"
"1","(-5200,7400)","0","pure_quanta","I74";
;
PART_NUMBER"CS00002JB13"
TOLERANCE"5%"
VALUE"0"
MATERIAL"CHIP"
WATTAGE"1/16W"
PACK_TYPE"0402LF"
LOCATION"PR4230"
CDS_LIB"pure_quanta"
$SEC"1"
CDS_SEC"1";
"B"
$PN"2"27;
"A"
$PN"1"62;
%"UNIVERSAL_GND"
"1","(-5375,8075)","3","logical_power","I77";
;
HDL_POWER"GND"
CDS_LIB"logical_power";
"A"18;
%"UNIVERSAL_GND"
"1","(-5375,8550)","3","logical_power","I78";
;
HDL_POWER"GND"
CDS_LIB"logical_power";
"A"19;
%"UNIVERSAL_GND"
"1","(-9225,2875)","0","logical_power","I8";
;
HDL_POWER"GND"
CDS_LIB"logical_power";
"A"8;
%"Q_RES"
"1","(-5500,8950)","0","pure_quanta","I80";
;
PART_NUMBER"CS-1002FB04"
VALUE"1"
TOLERANCE"1%"
MATERIAL"CHIP"
WATTAGE"1/16W"
PACK_TYPE"0402LF"
LOCATION"PR375"
CDS_LIB"pure_quanta"
LOCATION"PR375"
$SEC"1"
CDS_SEC"1";
"B"
$PN"2"2;
"A"
$PN"1"63;
%"VCC15"
"1","(-5025,9075)","0","logical_power","I81";
;
HDL_POWER"P3V3_AUX"
CDS_LIB"logical_power";
"A"2;
%"UNIVERSAL_GND"
"1","(-4100,3925)","0","logical_power","I83";
;
HDL_POWER"GND"
CDS_LIB"logical_power";
"A"20;
%"UNIVERSAL_GND"
"1","(-4575,4625)","0","logical_power","I84";
;
HDL_POWER"GND"
CDS_LIB"logical_power";
"A"21;
%"Q_RES"
"2","(-4425,4675)","0","pure_quanta","I85";
;
PART_NUMBER"CS21002FB06"
WATTAGE"1/16W"
MATERIAL"CHIP"
TOLERANCE"1%"
PACK_TYPE"0402LF"
VALUE"1K"
LOCATION"R2404"
CDS_LIB"pure_quanta"
LOCATION"R2404"
$SEC"1"
CDS_SEC"1";
"A"
$PN"1"6;
"B"
$PN"2"72;
%"VCC15"
"1","(-4425,4900)","0","logical_power","I86";
;
HDL_POWER"P3V3_AUX"
CDS_LIB"logical_power";
"A"6;
%"UNIVERSAL_GND"
"1","(-4575,5075)","0","logical_power","I87";
;
HDL_POWER"GND"
CDS_LIB"logical_power";
"A"22;
%"Q_CAP"
"1","(-9225,3175)","0","pure_quanta","I9";
;
PART_NUMBER"CH4104K1B00"
PACK_TYPE"0402"
VOLTAGE"25V"
VALUE"0.1UF"
MATERIAL"X7R"
TOLERANCE"10%"
LOCATION"PC624"
CDS_LIB"pure_quanta"
LOCATION"PC624"
$SEC"1"
CDS_SEC"1";
"B"
$PN"2"8;
"A"
$PN"1"39;
%"UNIVERSAL_GND"
"1","(-4575,5525)","0","logical_power","I90";
;
HDL_POWER"GND"
CDS_LIB"logical_power";
"A"23;
%"UNIVERSAL_GND"
"1","(-4575,5975)","0","logical_power","I91";
;
HDL_POWER"GND"
CDS_LIB"logical_power";
"A"24;
%"UNIVERSAL_GND"
"1","(-4575,6425)","0","logical_power","I92";
;
HDL_POWER"GND"
CDS_LIB"logical_power";
"A"25;
%"UNIVERSAL_GND"
"1","(-4575,6875)","0","logical_power","I93";
;
HDL_POWER"GND"
CDS_LIB"logical_power";
"A"26;
%"UNIVERSAL_GND"
"1","(-4575,7325)","0","logical_power","I94";
;
HDL_POWER"GND"
CDS_LIB"logical_power";
"A"27;
%"Q_RES"
"1","(-10725,3725)","0","pure_quanta","I95";
;
PART_NUMBER"CS23572FB05"
VALUE"3.57K"
TOLERANCE"1%"
PACK_TYPE"0402LF"
MATERIAL"CHIP"
WATTAGE"1/16W"
LOCATION"PR358"
CDS_LIB"pure_quanta"
$SEC"1"
CDS_SEC"1";
"B"
$PN"2"43;
"A"
$PN"1"7;
%"Q_CAP"
"1","(-6575,8750)","0","pure_quanta","I96";
;
PART_NUMBER"CH4104K1B00"
VALUE"0.1UF"
VOLTAGE"25V"
TOLERANCE"10%"
MATERIAL"EMPTY"
PACK_TYPE"0402"
LOCATION"PC2365"
CDS_LIB"pure_quanta"
$SEC"1"
CDS_SEC"1";
"B"
$PN"2"19;
"A"
$PN"1"63;
END.
